(kicad_pcb
	(version 20260206)
	(generator "pcbnew")
	(generator_version "10.0")
	(general
		(thickness 1.6)
		(legacy_teardrops no)
	)
	(paper "A4")
	(title_block
		(title "04192023_DAF0TMB3IC0_F0TG_MB_C_brd_V02_OCP.brd")
		(comment 1 "Grand Teton / footprints 1317-1323 of 8354")
	)
	(layers
		(0 "F.Cu" signal "TOP")
		(4 "In1.Cu" signal "GND")
		(6 "In2.Cu" signal "IN1")
		(8 "In3.Cu" signal "GND1")
		(10 "In4.Cu" signal "IN2")
		(12 "In5.Cu" signal "GND2")
		(14 "In6.Cu" signal "IN3")
		(16 "In7.Cu" signal "GND3")
		(18 "In8.Cu" signal "VCC")
		(20 "In9.Cu" signal "VCC1")
		(22 "In10.Cu" signal "GND4")
		(24 "In11.Cu" signal "IN4")
		(26 "In12.Cu" signal "GND5")
		(28 "In13.Cu" signal "IN5")
		(30 "In14.Cu" signal "GND6")
		(32 "In15.Cu" signal "IN6")
		(34 "In16.Cu" signal "GND7")
		(2 "B.Cu" signal "BOTTOM")
		(9 "F.Adhes" user "F.Adhesive")
		(11 "B.Adhes" user "B.Adhesive")
		(13 "F.Paste" user "Package Geometry/Pastemask Top")
		(15 "B.Paste" user "Package Geometry/Pastemask Bottom")
		(5 "F.SilkS" user "Ref Des/Silkscreen Top")
		(7 "B.SilkS" user "Ref Des/Silkscreen Bottom")
		(1 "F.Mask" user "Board Geometry/Soldermask Top")
		(3 "B.Mask" user "Board Geometry/Soldermask Bottom")
		(17 "Dwgs.User" user "User.Drawings")
		(19 "Cmts.User" user "User.Comments")
		(21 "Eco1.User" user "User.Eco1")
		(23 "Eco2.User" user "User.Eco2")
		(25 "Edge.Cuts" user "Board Geometry/Outline")
		(27 "Margin" user)
		(31 "F.CrtYd" user "Package Geometry/Place Bound Top")
		(29 "B.CrtYd" user "Package Geometry/Place Bound Bottom")
		(35 "F.Fab" user "Ref Des/Assembly Top")
		(33 "B.Fab" user "Ref Des/Assembly Bottom")
	)
	(footprint ""
		(layer "F.Cu")
		(at 31.585662 -419.249098 -90)
		(property "Reference" "R3276"
			(at 0 0 270)
			(layer "F.SilkS")
			(hide yes)
			(effects
				(font
					(size 1.27 1.27)
				)
			)
		)
		(property "Value" ""
			(at 0 0 270)
			(layer "F.Fab")
			(effects
				(font
					(size 1.27 1.27)
				)
			)
		)
		(duplicate_pad_numbers_are_jumpers no)
		(fp_line
			(start -0.7874 0.4064)
			(end -0.7874 -0.4064)
			(stroke
				(width 0.1524)
				(type default)
			)
			(layer "F.SilkS")
		)
		(fp_line
			(start 0.7874 0.4064)
			(end -0.7874 0.4064)
			(stroke
				(width 0.1524)
				(type default)
			)
			(layer "F.SilkS")
		)
		(fp_line
			(start -0.7874 -0.4064)
			(end 0.7874 -0.4064)
			(stroke
				(width 0.1524)
				(type default)
			)
			(layer "F.SilkS")
		)
		(fp_line
			(start 0.7874 -0.4064)
			(end 0.7874 0.4064)
			(stroke
				(width 0.1524)
				(type default)
			)
			(layer "F.SilkS")
		)
		(fp_line
			(start -0.67945 0.3048)
			(end -0.67945 -0.305054)
			(stroke
				(width 0.1)
				(type default)
			)
			(layer "F.Fab")
		)
		(fp_line
			(start -0.12065 0.3048)
			(end -0.67945 0.3048)
			(stroke
				(width 0.1)
				(type default)
			)
			(layer "F.Fab")
		)
		(fp_line
			(start 0.120396 0.3048)
			(end 0.120396 0.2794)
			(stroke
				(width 0.1)
				(type default)
			)
			(layer "F.Fab")
		)
		(fp_line
			(start 0.67945 0.3048)
			(end 0.120396 0.3048)
			(stroke
				(width 0.1)
				(type default)
			)
			(layer "F.Fab")
		)
		(fp_line
			(start -0.12065 0.2794)
			(end -0.12065 0.3048)
			(stroke
				(width 0.1)
				(type default)
			)
			(layer "F.Fab")
		)
		(fp_line
			(start 0.120396 0.2794)
			(end -0.12065 0.2794)
			(stroke
				(width 0.1)
				(type default)
			)
			(layer "F.Fab")
		)
		(fp_line
			(start -0.12065 -0.2794)
			(end 0.12065 -0.2794)
			(stroke
				(width 0.1)
				(type default)
			)
			(layer "F.Fab")
		)
		(fp_line
			(start 0.12065 -0.2794)
			(end 0.12065 -0.3048)
			(stroke
				(width 0.1)
				(type default)
			)
			(layer "F.Fab")
		)
		(fp_line
			(start 0.12065 -0.3048)
			(end 0.67945 -0.3048)
			(stroke
				(width 0.1)
				(type default)
			)
			(layer "F.Fab")
		)
		(fp_line
			(start 0.67945 -0.3048)
			(end 0.67945 0.3048)
			(stroke
				(width 0.1)
				(type default)
			)
			(layer "F.Fab")
		)
		(fp_line
			(start -0.67945 -0.305054)
			(end -0.12065 -0.305054)
			(stroke
				(width 0.1)
				(type default)
			)
			(layer "F.Fab")
		)
		(fp_line
			(start -0.12065 -0.305054)
			(end -0.12065 -0.2794)
			(stroke
				(width 0.1)
				(type default)
			)
			(layer "F.Fab")
		)
		(pad "1" smd circle
			(at -0.40005 0 270)
			(size 0 0)
			(layers "F.Cu" "F.Mask" "F.Paste")
			(net "FM_P2E_FGA")
		)
		(pad "2" smd circle
			(at 0.40005 0 270)
			(size 0 0)
			(layers "F.Cu" "F.Mask" "F.Paste")
			(net "GND")
		)
	)
	(footprint ""
		(layer "F.Cu")
		(at 330.775564 -140.414502 180)
		(property "Reference" "PC258"
			(at 0 0 180)
			(layer "F.SilkS")
			(hide yes)
			(effects
				(font
					(size 1.27 1.27)
				)
			)
		)
		(property "Value" ""
			(at 0 0 180)
			(layer "F.Fab")
			(effects
				(font
					(size 1.27 1.27)
				)
			)
		)
		(duplicate_pad_numbers_are_jumpers no)
		(fp_line
			(start 0.7874 0.4064)
			(end -0.7874 0.4064)
			(stroke
				(width 0.1524)
				(type default)
			)
			(layer "F.SilkS")
		)
		(fp_line
			(start 0.7874 -0.4064)
			(end 0.7874 0.4064)
			(stroke
				(width 0.1524)
				(type default)
			)
			(layer "F.SilkS")
		)
		(fp_line
			(start -0.7874 0.4064)
			(end -0.7874 -0.4064)
			(stroke
				(width 0.1524)
				(type default)
			)
			(layer "F.SilkS")
		)
		(fp_line
			(start -0.7874 -0.4064)
			(end 0.7874 -0.4064)
			(stroke
				(width 0.1524)
				(type default)
			)
			(layer "F.SilkS")
		)
		(fp_line
			(start 0.67945 0.3048)
			(end 0.120396 0.3048)
			(stroke
				(width 0.1)
				(type default)
			)
			(layer "F.Fab")
		)
		(fp_line
			(start 0.67945 -0.3048)
			(end 0.67945 0.3048)
			(stroke
				(width 0.1)
				(type default)
			)
			(layer "F.Fab")
		)
		(fp_line
			(start 0.12065 -0.2794)
			(end 0.12065 -0.3048)
			(stroke
				(width 0.1)
				(type default)
			)
			(layer "F.Fab")
		)
		(fp_line
			(start 0.12065 -0.3048)
			(end 0.67945 -0.3048)
			(stroke
				(width 0.1)
				(type default)
			)
			(layer "F.Fab")
		)
		(fp_line
			(start 0.120396 0.3048)
			(end 0.120396 0.2794)
			(stroke
				(width 0.1)
				(type default)
			)
			(layer "F.Fab")
		)
		(fp_line
			(start 0.120396 0.2794)
			(end -0.12065 0.2794)
			(stroke
				(width 0.1)
				(type default)
			)
			(layer "F.Fab")
		)
		(fp_line
			(start -0.12065 0.3048)
			(end -0.67945 0.3048)
			(stroke
				(width 0.1)
				(type default)
			)
			(layer "F.Fab")
		)
		(fp_line
			(start -0.12065 0.2794)
			(end -0.12065 0.3048)
			(stroke
				(width 0.1)
				(type default)
			)
			(layer "F.Fab")
		)
		(fp_line
			(start -0.12065 -0.2794)
			(end 0.12065 -0.2794)
			(stroke
				(width 0.1)
				(type default)
			)
			(layer "F.Fab")
		)
		(fp_line
			(start -0.12065 -0.305054)
			(end -0.12065 -0.2794)
			(stroke
				(width 0.1)
				(type default)
			)
			(layer "F.Fab")
		)
		(fp_line
			(start -0.67945 0.3048)
			(end -0.67945 -0.305054)
			(stroke
				(width 0.1)
				(type default)
			)
			(layer "F.Fab")
		)
		(fp_line
			(start -0.67945 -0.305054)
			(end -0.12065 -0.305054)
			(stroke
				(width 0.1)
				(type default)
			)
			(layer "F.Fab")
		)
		(pad "1" smd circle
			(at -0.40005 0 180)
			(size 0 0)
			(layers "F.Cu" "F.Mask" "F.Paste")
			(net "PVDD18_S5_P0_REF")
		)
		(pad "2" smd circle
			(at 0.40005 0 180)
			(size 0 0)
			(layers "F.Cu" "F.Mask" "F.Paste")
			(net "GND")
		)
	)
	(footprint ""
		(layer "F.Cu")
		(at 102.424738 -345.150948)
		(property "Reference" "PR426"
			(at 0 0 0)
			(layer "F.SilkS")
			(hide yes)
			(effects
				(font
					(size 1.27 1.27)
				)
			)
		)
		(property "Value" ""
			(at 0 0 0)
			(layer "F.Fab")
			(effects
				(font
					(size 1.27 1.27)
				)
			)
		)
		(duplicate_pad_numbers_are_jumpers no)
		(fp_line
			(start -0.7874 -0.4064)
			(end 0.7874 -0.4064)
			(stroke
				(width 0.1524)
				(type default)
			)
			(layer "F.SilkS")
		)
		(fp_line
			(start -0.7874 0.4064)
			(end -0.7874 -0.4064)
			(stroke
				(width 0.1524)
				(type default)
			)
			(layer "F.SilkS")
		)
		(fp_line
			(start 0.7874 -0.4064)
			(end 0.7874 0.4064)
			(stroke
				(width 0.1524)
				(type default)
			)
			(layer "F.SilkS")
		)
		(fp_line
			(start 0.7874 0.4064)
			(end -0.7874 0.4064)
			(stroke
				(width 0.1524)
				(type default)
			)
			(layer "F.SilkS")
		)
		(fp_line
			(start -0.67945 -0.305054)
			(end -0.12065 -0.305054)
			(stroke
				(width 0.1)
				(type default)
			)
			(layer "F.Fab")
		)
		(fp_line
			(start -0.67945 0.3048)
			(end -0.67945 -0.305054)
			(stroke
				(width 0.1)
				(type default)
			)
			(layer "F.Fab")
		)
		(fp_line
			(start -0.12065 -0.305054)
			(end -0.12065 -0.2794)
			(stroke
				(width 0.1)
				(type default)
			)
			(layer "F.Fab")
		)
		(fp_line
			(start -0.12065 -0.2794)
			(end 0.12065 -0.2794)
			(stroke
				(width 0.1)
				(type default)
			)
			(layer "F.Fab")
		)
		(fp_line
			(start -0.12065 0.2794)
			(end -0.12065 0.3048)
			(stroke
				(width 0.1)
				(type default)
			)
			(layer "F.Fab")
		)
		(fp_line
			(start -0.12065 0.3048)
			(end -0.67945 0.3048)
			(stroke
				(width 0.1)
				(type default)
			)
			(layer "F.Fab")
		)
		(fp_line
			(start 0.120396 0.2794)
			(end -0.12065 0.2794)
			(stroke
				(width 0.1)
				(type default)
			)
			(layer "F.Fab")
		)
		(fp_line
			(start 0.120396 0.3048)
			(end 0.120396 0.2794)
			(stroke
				(width 0.1)
				(type default)
			)
			(layer "F.Fab")
		)
		(fp_line
			(start 0.12065 -0.3048)
			(end 0.67945 -0.3048)
			(stroke
				(width 0.1)
				(type default)
			)
			(layer "F.Fab")
		)
		(fp_line
			(start 0.12065 -0.2794)
			(end 0.12065 -0.3048)
			(stroke
				(width 0.1)
				(type default)
			)
			(layer "F.Fab")
		)
		(fp_line
			(start 0.67945 -0.3048)
			(end 0.67945 0.3048)
			(stroke
				(width 0.1)
				(type default)
			)
			(layer "F.Fab")
		)
		(fp_line
			(start 0.67945 0.3048)
			(end 0.120396 0.3048)
			(stroke
				(width 0.1)
				(type default)
			)
			(layer "F.Fab")
		)
		(pad "1" smd circle
			(at -0.40005 0)
			(size 0 0)
			(layers "F.Cu" "F.Mask" "F.Paste")
			(net "PVDDCR_CPU1_P1_LSET6")
		)
		(pad "2" smd circle
			(at 0.40005 0)
			(size 0 0)
			(layers "F.Cu" "F.Mask" "F.Paste")
			(net "GND")
		)
	)
	(footprint ""
		(layer "F.Cu")
		(at 64.614298 -23.554182)
		(property "Reference" "PR3857"
			(at 0 0 0)
			(layer "F.SilkS")
			(hide yes)
			(effects
				(font
					(size 1.27 1.27)
				)
			)
		)
		(property "Value" ""
			(at 0 0 0)
			(layer "F.Fab")
			(effects
				(font
					(size 1.27 1.27)
				)
			)
		)
		(duplicate_pad_numbers_are_jumpers no)
		(fp_line
			(start -1.2954 -0.5842)
			(end 1.2954 -0.5842)
			(stroke
				(width 0.1524)
				(type default)
			)
			(layer "F.SilkS")
		)
		(fp_line
			(start -1.2954 0.5842)
			(end -1.2954 -0.5842)
			(stroke
				(width 0.1524)
				(type default)
			)
			(layer "F.SilkS")
		)
		(fp_line
			(start 1.2954 -0.5842)
			(end 1.2954 0.5842)
			(stroke
				(width 0.1524)
				(type default)
			)
			(layer "F.SilkS")
		)
		(fp_line
			(start 1.2954 0.5842)
			(end -1.2954 0.5842)
			(stroke
				(width 0.1524)
				(type default)
			)
			(layer "F.SilkS")
		)
		(fp_line
			(start -1.1938 -0.406654)
			(end -0.8636 -0.406654)
			(stroke
				(width 0.1)
				(type default)
			)
			(layer "F.Fab")
		)
		(fp_line
			(start -1.1938 0.4064)
			(end -1.1938 -0.406654)
			(stroke
				(width 0.1)
				(type default)
			)
			(layer "F.Fab")
		)
		(fp_line
			(start -0.8636 -0.4572)
			(end 0.8636 -0.4572)
			(stroke
				(width 0.1)
				(type default)
			)
			(layer "F.Fab")
		)
		(fp_line
			(start -0.8636 -0.406654)
			(end -0.8636 -0.4572)
			(stroke
				(width 0.1)
				(type default)
			)
			(layer "F.Fab")
		)
		(fp_line
			(start -0.8636 0.4064)
			(end -1.1938 0.4064)
			(stroke
				(width 0.1)
				(type default)
			)
			(layer "F.Fab")
		)
		(fp_line
			(start -0.8636 0.4318)
			(end -0.8636 0.4064)
			(stroke
				(width 0.1)
				(type default)
			)
			(layer "F.Fab")
		)
		(fp_line
			(start -0.8636 0.4572)
			(end -0.8636 0.4318)
			(stroke
				(width 0.1)
				(type default)
			)
			(layer "F.Fab")
		)
		(fp_line
			(start 0.8636 -0.4572)
			(end 0.8636 -0.406654)
			(stroke
				(width 0.1)
				(type default)
			)
			(layer "F.Fab")
		)
		(fp_line
			(start 0.8636 -0.406654)
			(end 1.1938 -0.406654)
			(stroke
				(width 0.1)
				(type default)
			)
			(layer "F.Fab")
		)
		(fp_line
			(start 0.8636 0.4064)
			(end 0.8636 0.4572)
			(stroke
				(width 0.1)
				(type default)
			)
			(layer "F.Fab")
		)
		(fp_line
			(start 0.8636 0.4572)
			(end -0.8636 0.4572)
			(stroke
				(width 0.1)
				(type default)
			)
			(layer "F.Fab")
		)
		(fp_line
			(start 1.1938 -0.406654)
			(end 1.1938 0.4064)
			(stroke
				(width 0.1)
				(type default)
			)
			(layer "F.Fab")
		)
		(fp_line
			(start 1.1938 0.4064)
			(end 0.8636 0.4064)
			(stroke
				(width 0.1)
				(type default)
			)
			(layer "F.Fab")
		)
		(pad "1" smd rect
			(at -0.7366 0 270)
			(size 0.7112 0.8128)
			(layers "F.Cu" "F.Mask" "F.Paste")
			(net "P12V_AUX")
		)
		(pad "2" smd rect
			(at 0.7366 0 270)
			(size 0.7112 0.8128)
			(layers "F.Cu" "F.Mask" "F.Paste")
			(net "P12V_OCP_AVIN_PD_2")
		)
	)
	(footprint ""
		(layer "F.Cu")
		(at 425.429934 -355.718364 -90)
		(property "Reference" "PC217"
			(at 0 0 270)
			(layer "F.SilkS")
			(hide yes)
			(effects
				(font
					(size 1.27 1.27)
				)
			)
		)
		(property "Value" ""
			(at 0 0 270)
			(layer "F.Fab")
			(effects
				(font
					(size 1.27 1.27)
				)
			)
		)
		(duplicate_pad_numbers_are_jumpers no)
		(fp_line
			(start -0.7874 0.4064)
			(end -0.7874 -0.4064)
			(stroke
				(width 0.1524)
				(type default)
			)
			(layer "F.SilkS")
		)
		(fp_line
			(start 0.7874 0.4064)
			(end -0.7874 0.4064)
			(stroke
				(width 0.1524)
				(type default)
			)
			(layer "F.SilkS")
		)
		(fp_line
			(start -0.7874 -0.4064)
			(end 0.7874 -0.4064)
			(stroke
				(width 0.1524)
				(type default)
			)
			(layer "F.SilkS")
		)
		(fp_line
			(start 0.7874 -0.4064)
			(end 0.7874 0.4064)
			(stroke
				(width 0.1524)
				(type default)
			)
			(layer "F.SilkS")
		)
		(fp_line
			(start -0.67945 0.3048)
			(end -0.67945 -0.305054)
			(stroke
				(width 0.1)
				(type default)
			)
			(layer "F.Fab")
		)
		(fp_line
			(start -0.12065 0.3048)
			(end -0.67945 0.3048)
			(stroke
				(width 0.1)
				(type default)
			)
			(layer "F.Fab")
		)
		(fp_line
			(start 0.120396 0.3048)
			(end 0.120396 0.2794)
			(stroke
				(width 0.1)
				(type default)
			)
			(layer "F.Fab")
		)
		(fp_line
			(start 0.67945 0.3048)
			(end 0.120396 0.3048)
			(stroke
				(width 0.1)
				(type default)
			)
			(layer "F.Fab")
		)
		(fp_line
			(start -0.12065 0.2794)
			(end -0.12065 0.3048)
			(stroke
				(width 0.1)
				(type default)
			)
			(layer "F.Fab")
		)
		(fp_line
			(start 0.120396 0.2794)
			(end -0.12065 0.2794)
			(stroke
				(width 0.1)
				(type default)
			)
			(layer "F.Fab")
		)
		(fp_line
			(start -0.12065 -0.2794)
			(end 0.12065 -0.2794)
			(stroke
				(width 0.1)
				(type default)
			)
			(layer "F.Fab")
		)
		(fp_line
			(start 0.12065 -0.2794)
			(end 0.12065 -0.3048)
			(stroke
				(width 0.1)
				(type default)
			)
			(layer "F.Fab")
		)
		(fp_line
			(start 0.12065 -0.3048)
			(end 0.67945 -0.3048)
			(stroke
				(width 0.1)
				(type default)
			)
			(layer "F.Fab")
		)
		(fp_line
			(start 0.67945 -0.3048)
			(end 0.67945 0.3048)
			(stroke
				(width 0.1)
				(type default)
			)
			(layer "F.Fab")
		)
		(fp_line
			(start -0.67945 -0.305054)
			(end -0.12065 -0.305054)
			(stroke
				(width 0.1)
				(type default)
			)
			(layer "F.Fab")
		)
		(fp_line
			(start -0.12065 -0.305054)
			(end -0.12065 -0.2794)
			(stroke
				(width 0.1)
				(type default)
			)
			(layer "F.Fab")
		)
		(pad "1" smd circle
			(at -0.40005 0 270)
			(size 0 0)
			(layers "F.Cu" "F.Mask" "F.Paste")
			(net "SW_PVDD11_S3_P0_BOOT1_RC")
		)
		(pad "2" smd circle
			(at 0.40005 0 270)
			(size 0 0)
			(layers "F.Cu" "F.Mask" "F.Paste")
			(net "SW_PVDD11_S3_P0_PH1")
		)
	)
	(footprint ""
		(layer "F.Cu")
		(at 40.386 -390.398 90)
		(property "Reference" "R727"
			(at 0 0 90)
			(layer "F.SilkS")
			(hide yes)
			(effects
				(font
					(size 1.27 1.27)
				)
			)
		)
		(property "Value" ""
			(at 0 0 90)
			(layer "F.Fab")
			(effects
				(font
					(size 1.27 1.27)
				)
			)
		)
		(duplicate_pad_numbers_are_jumpers no)
		(fp_line
			(start 0.32512 -0.175006)
			(end 0.32512 0.175006)
			(stroke
				(width 0.1)
				(type default)
			)
			(layer "F.Fab")
		)
		(fp_line
			(start -0.32512 -0.175006)
			(end 0.32512 -0.175006)
			(stroke
				(width 0.1)
				(type default)
			)
			(layer "F.Fab")
		)
		(fp_line
			(start 0.32512 0.175006)
			(end -0.32512 0.175006)
			(stroke
				(width 0.1)
				(type default)
			)
			(layer "F.Fab")
		)
		(fp_line
			(start -0.32512 0.175006)
			(end -0.32512 -0.175006)
			(stroke
				(width 0.1)
				(type default)
			)
			(layer "F.Fab")
		)
		(pad "1" smd rect
			(at -0.2667 0 90)
			(size 0.3048 0.381)
			(layers "F.Cu" "F.Mask" "F.Paste")
			(net "P1V8_CPU1_RT_1D")
		)
		(pad "2" smd rect
			(at 0.2667 0 270)
			(size 0.3048 0.381)
			(layers "F.Cu" "F.Mask" "F.Paste")
			(net "MODE_RT_CPU1_P0")
		)
	)
	(footprint ""
		(layer "F.Cu")
		(at 63.194438 -29.398722 180)
		(property "Reference" "PR3851"
			(at 0 0 180)
			(layer "F.SilkS")
			(hide yes)
			(effects
				(font
					(size 1.27 1.27)
				)
			)
		)
		(property "Value" ""
			(at 0 0 180)
			(layer "F.Fab")
			(effects
				(font
					(size 1.27 1.27)
				)
			)
		)
		(duplicate_pad_numbers_are_jumpers no)
		(fp_line
			(start 0.7874 0.4064)
			(end -0.7874 0.4064)
			(stroke
				(width 0.1524)
				(type default)
			)
			(layer "F.SilkS")
		)
		(fp_line
			(start 0.7874 -0.4064)
			(end 0.7874 0.4064)
			(stroke
				(width 0.1524)
				(type default)
			)
			(layer "F.SilkS")
		)
		(fp_line
			(start -0.7874 0.4064)
			(end -0.7874 -0.4064)
			(stroke
				(width 0.1524)
				(type default)
			)
			(layer "F.SilkS")
		)
		(fp_line
			(start -0.7874 -0.4064)
			(end 0.7874 -0.4064)
			(stroke
				(width 0.1524)
				(type default)
			)
			(layer "F.SilkS")
		)
		(fp_line
			(start 0.67945 0.3048)
			(end 0.120396 0.3048)
			(stroke
				(width 0.1)
				(type default)
			)
			(layer "F.Fab")
		)
		(fp_line
			(start 0.67945 -0.3048)
			(end 0.67945 0.3048)
			(stroke
				(width 0.1)
				(type default)
			)
			(layer "F.Fab")
		)
		(fp_line
			(start 0.12065 -0.2794)
			(end 0.12065 -0.3048)
			(stroke
				(width 0.1)
				(type default)
			)
			(layer "F.Fab")
		)
		(fp_line
			(start 0.12065 -0.3048)
			(end 0.67945 -0.3048)
			(stroke
				(width 0.1)
				(type default)
			)
			(layer "F.Fab")
		)
		(fp_line
			(start 0.120396 0.3048)
			(end 0.120396 0.2794)
			(stroke
				(width 0.1)
				(type default)
			)
			(layer "F.Fab")
		)
		(fp_line
			(start 0.120396 0.2794)
			(end -0.12065 0.2794)
			(stroke
				(width 0.1)
				(type default)
			)
			(layer "F.Fab")
		)
		(fp_line
			(start -0.12065 0.3048)
			(end -0.67945 0.3048)
			(stroke
				(width 0.1)
				(type default)
			)
			(layer "F.Fab")
		)
		(fp_line
			(start -0.12065 0.2794)
			(end -0.12065 0.3048)
			(stroke
				(width 0.1)
				(type default)
			)
			(layer "F.Fab")
		)
		(fp_line
			(start -0.12065 -0.2794)
			(end 0.12065 -0.2794)
			(stroke
				(width 0.1)
				(type default)
			)
			(layer "F.Fab")
		)
		(fp_line
			(start -0.12065 -0.305054)
			(end -0.12065 -0.2794)
			(stroke
				(width 0.1)
				(type default)
			)
			(layer "F.Fab")
		)
		(fp_line
			(start -0.67945 0.3048)
			(end -0.67945 -0.305054)
			(stroke
				(width 0.1)
				(type default)
			)
			(layer "F.Fab")
		)
		(fp_line
			(start -0.67945 -0.305054)
			(end -0.12065 -0.305054)
			(stroke
				(width 0.1)
				(type default)
			)
			(layer "F.Fab")
		)
		(pad "1" smd circle
			(at -0.40005 0 180)
			(size 0 0)
			(layers "F.Cu" "F.Mask" "F.Paste")
			(net "P12V_OCP_FLTB_2")
		)
		(pad "2" smd circle
			(at 0.40005 0 180)
			(size 0 0)
			(layers "F.Cu" "F.Mask" "F.Paste")
			(net "P3V3_AUX")
		)
	)
)
